(kicad_pcb
	(version 20260206)
	(generator "pcbnew")
	(generator_version "10.0")
	(general
		(thickness 1.6)
		(legacy_teardrops no)
	)
	(paper "A4")
	(title_block
		(title "01162023_DA0F0TEBIF0_F0T_Expander_BD_F_brd_V02_OCP.brd")
		(comment 1 "Grand Teton / footprints 6592-6599 of 9728")
	)
	(layers
		(0 "F.Cu" signal "TOP")
		(4 "In1.Cu" signal "GND")
		(6 "In2.Cu" signal "VCC")
		(8 "In3.Cu" signal "VCC1")
		(10 "In4.Cu" signal "GND1")
		(12 "In5.Cu" signal "IN1")
		(14 "In6.Cu" signal "GND2")
		(16 "In7.Cu" signal "IN2")
		(18 "In8.Cu" signal "GND3")
		(20 "In9.Cu" signal "IN3")
		(22 "In10.Cu" signal "GND4")
		(24 "In11.Cu" signal "IN4")
		(26 "In12.Cu" signal "GND5")
		(28 "In13.Cu" signal "IN5")
		(30 "In14.Cu" signal "GND6")
		(32 "In15.Cu" signal "IN6")
		(34 "In16.Cu" signal "GND7")
		(2 "B.Cu" signal "BOTTOM")
		(9 "F.Adhes" user "F.Adhesive")
		(11 "B.Adhes" user "B.Adhesive")
		(13 "F.Paste" user "Package Geometry/Pastemask Top")
		(15 "B.Paste" user "Package Geometry/Pastemask Bottom")
		(5 "F.SilkS" user "Ref Des/Silkscreen Top")
		(7 "B.SilkS" user "Ref Des/Silkscreen Bottom")
		(1 "F.Mask" user "Board Geometry/Soldermask Top")
		(3 "B.Mask" user "Board Geometry/Soldermask Bottom")
		(17 "Dwgs.User" user "User.Drawings")
		(19 "Cmts.User" user "User.Comments")
		(21 "Eco1.User" user "User.Eco1")
		(23 "Eco2.User" user "User.Eco2")
		(25 "Edge.Cuts" user "Board Geometry/Outline")
		(27 "Margin" user)
		(31 "F.CrtYd" user "Package Geometry/Place Bound Top")
		(29 "B.CrtYd" user "Package Geometry/Place Bound Bottom")
		(35 "F.Fab" user "Ref Des/Assembly Top")
		(33 "B.Fab" user "Ref Des/Assembly Bottom")
	)
	(footprint ""
		(layer "F.Cu")
		(at 375.690384 -250.070874 -90)
		(property "Reference" "R1410"
			(at 0 0 270)
			(layer "F.SilkS")
			(hide yes)
			(effects
				(font
					(size 1.27 1.27)
				)
			)
		)
		(property "Value" ""
			(at 0 0 270)
			(layer "F.Fab")
			(effects
				(font
					(size 1.27 1.27)
				)
			)
		)
		(duplicate_pad_numbers_are_jumpers no)
		(fp_line
			(start -0.7874 0.4064)
			(end -0.7874 -0.4064)
			(stroke
				(width 0.1524)
				(type default)
			)
			(layer "F.SilkS")
		)
		(fp_line
			(start 0.7874 0.4064)
			(end -0.7874 0.4064)
			(stroke
				(width 0.1524)
				(type default)
			)
			(layer "F.SilkS")
		)
		(fp_line
			(start -0.7874 -0.4064)
			(end 0.7874 -0.4064)
			(stroke
				(width 0.1524)
				(type default)
			)
			(layer "F.SilkS")
		)
		(fp_line
			(start 0.7874 -0.4064)
			(end 0.7874 0.4064)
			(stroke
				(width 0.1524)
				(type default)
			)
			(layer "F.SilkS")
		)
		(fp_line
			(start -0.67945 0.3048)
			(end -0.67945 -0.305054)
			(stroke
				(width 0.1)
				(type default)
			)
			(layer "F.Fab")
		)
		(fp_line
			(start -0.12065 0.3048)
			(end -0.67945 0.3048)
			(stroke
				(width 0.1)
				(type default)
			)
			(layer "F.Fab")
		)
		(fp_line
			(start 0.120396 0.3048)
			(end 0.120396 0.2794)
			(stroke
				(width 0.1)
				(type default)
			)
			(layer "F.Fab")
		)
		(fp_line
			(start 0.67945 0.3048)
			(end 0.120396 0.3048)
			(stroke
				(width 0.1)
				(type default)
			)
			(layer "F.Fab")
		)
		(fp_line
			(start -0.12065 0.2794)
			(end -0.12065 0.3048)
			(stroke
				(width 0.1)
				(type default)
			)
			(layer "F.Fab")
		)
		(fp_line
			(start 0.120396 0.2794)
			(end -0.12065 0.2794)
			(stroke
				(width 0.1)
				(type default)
			)
			(layer "F.Fab")
		)
		(fp_line
			(start -0.12065 -0.2794)
			(end 0.12065 -0.2794)
			(stroke
				(width 0.1)
				(type default)
			)
			(layer "F.Fab")
		)
		(fp_line
			(start 0.12065 -0.2794)
			(end 0.12065 -0.3048)
			(stroke
				(width 0.1)
				(type default)
			)
			(layer "F.Fab")
		)
		(fp_line
			(start 0.12065 -0.3048)
			(end 0.67945 -0.3048)
			(stroke
				(width 0.1)
				(type default)
			)
			(layer "F.Fab")
		)
		(fp_line
			(start 0.67945 -0.3048)
			(end 0.67945 0.3048)
			(stroke
				(width 0.1)
				(type default)
			)
			(layer "F.Fab")
		)
		(fp_line
			(start -0.67945 -0.305054)
			(end -0.12065 -0.305054)
			(stroke
				(width 0.1)
				(type default)
			)
			(layer "F.Fab")
		)
		(fp_line
			(start -0.12065 -0.305054)
			(end -0.12065 -0.2794)
			(stroke
				(width 0.1)
				(type default)
			)
			(layer "F.Fab")
		)
		(pad "1" smd circle
			(at -0.40005 0 270)
			(size 0 0)
			(layers "F.Cu" "F.Mask" "F.Paste")
			(net "PEX3_MODE_SEL5")
		)
		(pad "2" smd circle
			(at 0.40005 0 270)
			(size 0 0)
			(layers "F.Cu" "F.Mask" "F.Paste")
			(net "P1V8_PEX")
		)
	)
	(footprint ""
		(layer "F.Cu")
		(at 433.403248 -59.571636 90)
		(property "Reference" "PR285"
			(at 0 0 90)
			(layer "F.SilkS")
			(hide yes)
			(effects
				(font
					(size 1.27 1.27)
				)
			)
		)
		(property "Value" ""
			(at 0 0 90)
			(layer "F.Fab")
			(effects
				(font
					(size 1.27 1.27)
				)
			)
		)
		(duplicate_pad_numbers_are_jumpers no)
		(fp_line
			(start 0.7874 -0.4064)
			(end 0.7874 0.4064)
			(stroke
				(width 0.1524)
				(type default)
			)
			(layer "F.SilkS")
		)
		(fp_line
			(start -0.7874 -0.4064)
			(end 0.7874 -0.4064)
			(stroke
				(width 0.1524)
				(type default)
			)
			(layer "F.SilkS")
		)
		(fp_line
			(start 0.7874 0.4064)
			(end -0.7874 0.4064)
			(stroke
				(width 0.1524)
				(type default)
			)
			(layer "F.SilkS")
		)
		(fp_line
			(start -0.7874 0.4064)
			(end -0.7874 -0.4064)
			(stroke
				(width 0.1524)
				(type default)
			)
			(layer "F.SilkS")
		)
		(fp_line
			(start -0.12065 -0.305054)
			(end -0.12065 -0.2794)
			(stroke
				(width 0.1)
				(type default)
			)
			(layer "F.Fab")
		)
		(fp_line
			(start -0.67945 -0.305054)
			(end -0.12065 -0.305054)
			(stroke
				(width 0.1)
				(type default)
			)
			(layer "F.Fab")
		)
		(fp_line
			(start 0.67945 -0.3048)
			(end 0.67945 0.3048)
			(stroke
				(width 0.1)
				(type default)
			)
			(layer "F.Fab")
		)
		(fp_line
			(start 0.12065 -0.3048)
			(end 0.67945 -0.3048)
			(stroke
				(width 0.1)
				(type default)
			)
			(layer "F.Fab")
		)
		(fp_line
			(start 0.12065 -0.2794)
			(end 0.12065 -0.3048)
			(stroke
				(width 0.1)
				(type default)
			)
			(layer "F.Fab")
		)
		(fp_line
			(start -0.12065 -0.2794)
			(end 0.12065 -0.2794)
			(stroke
				(width 0.1)
				(type default)
			)
			(layer "F.Fab")
		)
		(fp_line
			(start 0.120396 0.2794)
			(end -0.12065 0.2794)
			(stroke
				(width 0.1)
				(type default)
			)
			(layer "F.Fab")
		)
		(fp_line
			(start -0.12065 0.2794)
			(end -0.12065 0.3048)
			(stroke
				(width 0.1)
				(type default)
			)
			(layer "F.Fab")
		)
		(fp_line
			(start 0.67945 0.3048)
			(end 0.120396 0.3048)
			(stroke
				(width 0.1)
				(type default)
			)
			(layer "F.Fab")
		)
		(fp_line
			(start 0.120396 0.3048)
			(end 0.120396 0.2794)
			(stroke
				(width 0.1)
				(type default)
			)
			(layer "F.Fab")
		)
		(fp_line
			(start -0.12065 0.3048)
			(end -0.67945 0.3048)
			(stroke
				(width 0.1)
				(type default)
			)
			(layer "F.Fab")
		)
		(fp_line
			(start -0.67945 0.3048)
			(end -0.67945 -0.305054)
			(stroke
				(width 0.1)
				(type default)
			)
			(layer "F.Fab")
		)
		(pad "1" smd circle
			(at -0.40005 0 90)
			(size 0 0)
			(layers "F.Cu" "F.Mask" "F.Paste")
			(net "P3V3_SSD15_OCP")
		)
		(pad "2" smd circle
			(at 0.40005 0 90)
			(size 0 0)
			(layers "F.Cu" "F.Mask" "F.Paste")
			(net "GND")
		)
	)
	(footprint ""
		(layer "F.Cu")
		(at 410.092652 -158.080202 90)
		(property "Reference" "R3310"
			(at 0 0 90)
			(layer "F.SilkS")
			(hide yes)
			(effects
				(font
					(size 1.27 1.27)
				)
			)
		)
		(property "Value" ""
			(at 0 0 90)
			(layer "F.Fab")
			(effects
				(font
					(size 1.27 1.27)
				)
			)
		)
		(duplicate_pad_numbers_are_jumpers no)
		(fp_line
			(start 0.7874 -0.4064)
			(end 0.7874 0.4064)
			(stroke
				(width 0.1524)
				(type default)
			)
			(layer "F.SilkS")
		)
		(fp_line
			(start -0.7874 -0.4064)
			(end 0.7874 -0.4064)
			(stroke
				(width 0.1524)
				(type default)
			)
			(layer "F.SilkS")
		)
		(fp_line
			(start 0.7874 0.4064)
			(end -0.7874 0.4064)
			(stroke
				(width 0.1524)
				(type default)
			)
			(layer "F.SilkS")
		)
		(fp_line
			(start -0.7874 0.4064)
			(end -0.7874 -0.4064)
			(stroke
				(width 0.1524)
				(type default)
			)
			(layer "F.SilkS")
		)
		(fp_line
			(start -0.12065 -0.305054)
			(end -0.12065 -0.2794)
			(stroke
				(width 0.1)
				(type default)
			)
			(layer "F.Fab")
		)
		(fp_line
			(start -0.67945 -0.305054)
			(end -0.12065 -0.305054)
			(stroke
				(width 0.1)
				(type default)
			)
			(layer "F.Fab")
		)
		(fp_line
			(start 0.67945 -0.3048)
			(end 0.67945 0.3048)
			(stroke
				(width 0.1)
				(type default)
			)
			(layer "F.Fab")
		)
		(fp_line
			(start 0.12065 -0.3048)
			(end 0.67945 -0.3048)
			(stroke
				(width 0.1)
				(type default)
			)
			(layer "F.Fab")
		)
		(fp_line
			(start 0.12065 -0.2794)
			(end 0.12065 -0.3048)
			(stroke
				(width 0.1)
				(type default)
			)
			(layer "F.Fab")
		)
		(fp_line
			(start -0.12065 -0.2794)
			(end 0.12065 -0.2794)
			(stroke
				(width 0.1)
				(type default)
			)
			(layer "F.Fab")
		)
		(fp_line
			(start 0.120396 0.2794)
			(end -0.12065 0.2794)
			(stroke
				(width 0.1)
				(type default)
			)
			(layer "F.Fab")
		)
		(fp_line
			(start -0.12065 0.2794)
			(end -0.12065 0.3048)
			(stroke
				(width 0.1)
				(type default)
			)
			(layer "F.Fab")
		)
		(fp_line
			(start 0.67945 0.3048)
			(end 0.120396 0.3048)
			(stroke
				(width 0.1)
				(type default)
			)
			(layer "F.Fab")
		)
		(fp_line
			(start 0.120396 0.3048)
			(end 0.120396 0.2794)
			(stroke
				(width 0.1)
				(type default)
			)
			(layer "F.Fab")
		)
		(fp_line
			(start -0.12065 0.3048)
			(end -0.67945 0.3048)
			(stroke
				(width 0.1)
				(type default)
			)
			(layer "F.Fab")
		)
		(fp_line
			(start -0.67945 0.3048)
			(end -0.67945 -0.305054)
			(stroke
				(width 0.1)
				(type default)
			)
			(layer "F.Fab")
		)
		(pad "1" smd circle
			(at -0.40005 0 90)
			(size 0 0)
			(layers "F.Cu" "F.Mask" "F.Paste")
			(net "FM_SYS_THROTTLE_R")
		)
		(pad "2" smd circle
			(at 0.40005 0 90)
			(size 0 0)
			(layers "F.Cu" "F.Mask" "F.Paste")
			(net "FM_SYS_THROTTLE_NIC6")
		)
	)
	(footprint ""
		(layer "F.Cu")
		(at 118.054628 -356.244906 90)
		(property "Reference" "C346"
			(at 0 0 90)
			(layer "F.SilkS")
			(hide yes)
			(effects
				(font
					(size 1.27 1.27)
				)
			)
		)
		(property "Value" ""
			(at 0 0 90)
			(layer "F.Fab")
			(effects
				(font
					(size 1.27 1.27)
				)
			)
		)
		(duplicate_pad_numbers_are_jumpers no)
		(fp_line
			(start 0.299974 -0.150114)
			(end 0.299974 0.150114)
			(stroke
				(width 0.1)
				(type default)
			)
			(layer "F.Fab")
		)
		(fp_line
			(start -0.299974 -0.150114)
			(end 0.299974 -0.150114)
			(stroke
				(width 0.1)
				(type default)
			)
			(layer "F.Fab")
		)
		(fp_line
			(start 0.299974 0.150114)
			(end -0.299974 0.150114)
			(stroke
				(width 0.1)
				(type default)
			)
			(layer "F.Fab")
		)
		(fp_line
			(start -0.299974 0.150114)
			(end -0.299974 -0.150114)
			(stroke
				(width 0.1)
				(type default)
			)
			(layer "F.Fab")
		)
		(pad "1" smd rect
			(at -0.2667 0 90)
			(size 0.3048 0.381)
			(layers "F.Cu" "F.Mask" "F.Paste")
			(net "P5E_PEX1_STN6_TX_DP<108>")
		)
		(pad "2" smd rect
			(at 0.2667 0 90)
			(size 0.3048 0.381)
			(layers "F.Cu" "F.Mask" "F.Paste")
			(net "P5E_PEX1_STN6_TX_C_DP<108>")
		)
	)
	(footprint ""
		(layer "F.Cu")
		(at 393.8397 -350.098614 90)
		(property "Reference" "C741"
			(at 0 0 90)
			(layer "F.SilkS")
			(hide yes)
			(effects
				(font
					(size 1.27 1.27)
				)
			)
		)
		(property "Value" ""
			(at 0 0 90)
			(layer "F.Fab")
			(effects
				(font
					(size 1.27 1.27)
				)
			)
		)
		(duplicate_pad_numbers_are_jumpers no)
		(fp_line
			(start 0.299974 -0.150114)
			(end 0.299974 0.150114)
			(stroke
				(width 0.1)
				(type default)
			)
			(layer "F.Fab")
		)
		(fp_line
			(start -0.299974 -0.150114)
			(end 0.299974 -0.150114)
			(stroke
				(width 0.1)
				(type default)
			)
			(layer "F.Fab")
		)
		(fp_line
			(start 0.299974 0.150114)
			(end -0.299974 0.150114)
			(stroke
				(width 0.1)
				(type default)
			)
			(layer "F.Fab")
		)
		(fp_line
			(start -0.299974 0.150114)
			(end -0.299974 -0.150114)
			(stroke
				(width 0.1)
				(type default)
			)
			(layer "F.Fab")
		)
		(pad "1" smd rect
			(at -0.2667 0 90)
			(size 0.3048 0.381)
			(layers "F.Cu" "F.Mask" "F.Paste")
			(net "P5E_PEX3_STN5_TX_DN<90>")
		)
		(pad "2" smd rect
			(at 0.2667 0 90)
			(size 0.3048 0.381)
			(layers "F.Cu" "F.Mask" "F.Paste")
			(net "P5E_PEX3_STN5_TX_C_DN<90>")
		)
	)
	(footprint ""
		(layer "F.Cu")
		(at 271.480534 -100.203254)
		(property "Reference" "C486"
			(at 0 0 0)
			(layer "F.SilkS")
			(hide yes)
			(effects
				(font
					(size 1.27 1.27)
				)
			)
		)
		(property "Value" ""
			(at 0 0 0)
			(layer "F.Fab")
			(effects
				(font
					(size 1.27 1.27)
				)
			)
		)
		(duplicate_pad_numbers_are_jumpers no)
		(fp_line
			(start -0.299974 -0.150114)
			(end 0.299974 -0.150114)
			(stroke
				(width 0.1)
				(type default)
			)
			(layer "F.Fab")
		)
		(fp_line
			(start -0.299974 0.150114)
			(end -0.299974 -0.150114)
			(stroke
				(width 0.1)
				(type default)
			)
			(layer "F.Fab")
		)
		(fp_line
			(start 0.299974 -0.150114)
			(end 0.299974 0.150114)
			(stroke
				(width 0.1)
				(type default)
			)
			(layer "F.Fab")
		)
		(fp_line
			(start 0.299974 0.150114)
			(end -0.299974 0.150114)
			(stroke
				(width 0.1)
				(type default)
			)
			(layer "F.Fab")
		)
		(pad "1" smd rect
			(at -0.2667 0)
			(size 0.3048 0.381)
			(layers "F.Cu" "F.Mask" "F.Paste")
			(net "P5E_PEX2_STN1_TX_DN<16>")
		)
		(pad "2" smd rect
			(at 0.2667 0)
			(size 0.3048 0.381)
			(layers "F.Cu" "F.Mask" "F.Paste")
			(net "P5E_PEX2_STN1_TX_C_DN<16>")
		)
	)
	(footprint ""
		(layer "F.Cu")
		(at 123.71324 -135.058404 180)
		(property "Reference" "C2857"
			(at 0 0 180)
			(layer "F.SilkS")
			(hide yes)
			(effects
				(font
					(size 1.27 1.27)
				)
			)
		)
		(property "Value" ""
			(at 0 0 180)
			(layer "F.Fab")
			(effects
				(font
					(size 1.27 1.27)
				)
			)
		)
		(duplicate_pad_numbers_are_jumpers no)
		(fp_line
			(start 0.7874 0.4064)
			(end -0.7874 0.4064)
			(stroke
				(width 0.1524)
				(type default)
			)
			(layer "F.SilkS")
		)
		(fp_line
			(start 0.7874 -0.4064)
			(end 0.7874 0.4064)
			(stroke
				(width 0.1524)
				(type default)
			)
			(layer "F.SilkS")
		)
		(fp_line
			(start -0.7874 0.4064)
			(end -0.7874 -0.4064)
			(stroke
				(width 0.1524)
				(type default)
			)
			(layer "F.SilkS")
		)
		(fp_line
			(start -0.7874 -0.4064)
			(end 0.7874 -0.4064)
			(stroke
				(width 0.1524)
				(type default)
			)
			(layer "F.SilkS")
		)
		(fp_line
			(start 0.67945 0.3048)
			(end 0.120396 0.3048)
			(stroke
				(width 0.1)
				(type default)
			)
			(layer "F.Fab")
		)
		(fp_line
			(start 0.67945 -0.3048)
			(end 0.67945 0.3048)
			(stroke
				(width 0.1)
				(type default)
			)
			(layer "F.Fab")
		)
		(fp_line
			(start 0.12065 -0.2794)
			(end 0.12065 -0.3048)
			(stroke
				(width 0.1)
				(type default)
			)
			(layer "F.Fab")
		)
		(fp_line
			(start 0.12065 -0.3048)
			(end 0.67945 -0.3048)
			(stroke
				(width 0.1)
				(type default)
			)
			(layer "F.Fab")
		)
		(fp_line
			(start 0.120396 0.3048)
			(end 0.120396 0.2794)
			(stroke
				(width 0.1)
				(type default)
			)
			(layer "F.Fab")
		)
		(fp_line
			(start 0.120396 0.2794)
			(end -0.12065 0.2794)
			(stroke
				(width 0.1)
				(type default)
			)
			(layer "F.Fab")
		)
		(fp_line
			(start -0.12065 0.3048)
			(end -0.67945 0.3048)
			(stroke
				(width 0.1)
				(type default)
			)
			(layer "F.Fab")
		)
		(fp_line
			(start -0.12065 0.2794)
			(end -0.12065 0.3048)
			(stroke
				(width 0.1)
				(type default)
			)
			(layer "F.Fab")
		)
		(fp_line
			(start -0.12065 -0.2794)
			(end 0.12065 -0.2794)
			(stroke
				(width 0.1)
				(type default)
			)
			(layer "F.Fab")
		)
		(fp_line
			(start -0.12065 -0.305054)
			(end -0.12065 -0.2794)
			(stroke
				(width 0.1)
				(type default)
			)
			(layer "F.Fab")
		)
		(fp_line
			(start -0.67945 0.3048)
			(end -0.67945 -0.305054)
			(stroke
				(width 0.1)
				(type default)
			)
			(layer "F.Fab")
		)
		(fp_line
			(start -0.67945 -0.305054)
			(end -0.12065 -0.305054)
			(stroke
				(width 0.1)
				(type default)
			)
			(layer "F.Fab")
		)
		(pad "1" smd circle
			(at -0.40005 0 180)
			(size 0 0)
			(layers "F.Cu" "F.Mask" "F.Paste")
			(net "P12V_NIC2_EN_R")
		)
		(pad "2" smd circle
			(at 0.40005 0 180)
			(size 0 0)
			(layers "F.Cu" "F.Mask" "F.Paste")
			(net "GND")
		)
	)
	(footprint ""
		(layer "F.Cu")
		(at 230.664258 -103.328216 -90)
		(property "Reference" "PD8"
			(at 4.217416 -2.712212 90)
			(unlocked yes)
			(layer "F.SilkS")
			(effects
				(font
					(size 0.7874 0.5842)
					(thickness 0.1524)
				)
				(justify left)
			)
		)
		(property "Value" ""
			(at 0 0 270)
			(layer "F.Fab")
			(effects
				(font
					(size 1.27 1.27)
				)
			)
		)
		(duplicate_pad_numbers_are_jumpers no)
		(fp_line
			(start -3.656584 1.970024)
			(end 4.240784 1.970024)
			(stroke
				(width 0.1524)
				(type default)
			)
			(layer "F.SilkS")
		)
		(fp_line
			(start 4.240784 1.970024)
			(end 4.240784 -1.970024)
			(stroke
				(width 0.1524)
				(type default)
			)
			(layer "F.SilkS")
		)
		(fp_line
			(start -3.656584 -1.970024)
			(end -3.656584 1.970024)
			(stroke
				(width 0.1524)
				(type default)
			)
			(layer "F.SilkS")
		)
		(fp_line
			(start 4.240784 -1.970024)
			(end -3.656584 -1.970024)
			(stroke
				(width 0.1524)
				(type default)
			)
			(layer "F.SilkS")
		)
		(fp_poly
			(pts
				(xy 3.580384 1.970024) (xy 3.580384 -1.970024) (xy 4.240784 -1.970024) (xy 4.240784 1.970024)
			)
			(stroke
				(width 0)
				(type default)
			)
			(fill yes)
			(layer "F.SilkS")
		)
		(fp_line
			(start -2.3749 1.970024)
			(end 2.3749 1.970024)
			(stroke
				(width 0.1)
				(type default)
			)
			(layer "F.Fab")
		)
		(fp_line
			(start 2.3749 1.970024)
			(end 2.3749 -1.970024)
			(stroke
				(width 0.1)
				(type default)
			)
			(layer "F.Fab")
		)
		(fp_line
			(start -2.3749 -1.970024)
			(end -2.3749 1.970024)
			(stroke
				(width 0.1)
				(type default)
			)
			(layer "F.Fab")
		)
		(fp_line
			(start 2.3749 -1.970024)
			(end -2.3749 -1.970024)
			(stroke
				(width 0.1)
				(type default)
			)
			(layer "F.Fab")
		)
		(fp_text user "+"
			(at -4.9784 -0.23495 270)
			(unlocked yes)
			(layer "F.Fab")
			(effects
				(font
					(size 1.905 1.4224)
					(thickness 0.1524)
				)
				(justify left)
			)
		)
		(fp_text user "-"
			(at 4.1656 -0.23495 270)
			(unlocked yes)
			(layer "F.Fab")
			(effects
				(font
					(size 1.905 1.4224)
					(thickness 0.1524)
				)
				(justify left)
			)
		)
		(pad "A" smd rect
			(at -2.450084 0 270)
			(size 2.159 2.2606)
			(layers "F.Cu" "F.Mask" "F.Paste")
			(net "GND")
		)
		(pad "C" smd rect
			(at 2.450084 0 270)
			(size 2.159 2.2606)
			(layers "F.Cu" "F.Mask" "F.Paste")
			(net "P12V_AUX")
		)
	)
)
